# T6G (Grand Teton) — schematic netlist excerpt (pin names and nets, part order shuffled) for the footprints in the layout excerpt that follows; sources: Cadence DE-HDL packaged netlist, KiCad conversion of 04192023_DAF0TMB3IC0_F0TG_MB_C_brd_V02_OCP.brd

R1181  Q_RES  0 5% CHIP  pkg 0402LF  page 140 : A = P12V_OCP_V3_2_BUF_EN_R ; B = P12V_OCP_EN_2_R
PR4002  Q_RES  15K 1% CHIP  pkg 0402LF  page 152 : A = P12V_SCM_OV ; B = GND

(kicad_pcb
	(version 20260206)
	(generator "pcbnew")
	(generator_version "10.0")
	(general
		(thickness 1.6)
		(legacy_teardrops no)
	)
	(paper "A4")
	(title_block
		(title "04192023_DAF0TMB3IC0_F0TG_MB_C_brd_V02_OCP.brd")
		(comment 1 "Grand Teton / footprints 2806-2807 of 8354")
	)
	(layers
		(0 "F.Cu" signal "TOP")
		(4 "In1.Cu" signal "GND")
		(6 "In2.Cu" signal "IN1")
		(8 "In3.Cu" signal "GND1")
		(10 "In4.Cu" signal "IN2")
		(12 "In5.Cu" signal "GND2")
		(14 "In6.Cu" signal "IN3")
		(16 "In7.Cu" signal "GND3")
		(18 "In8.Cu" signal "VCC")
		(20 "In9.Cu" signal "VCC1")
		(22 "In10.Cu" signal "GND4")
		(24 "In11.Cu" signal "IN4")
		(26 "In12.Cu" signal "GND5")
		(28 "In13.Cu" signal "IN5")
		(30 "In14.Cu" signal "GND6")
		(32 "In15.Cu" signal "IN6")
		(34 "In16.Cu" signal "GND7")
		(2 "B.Cu" signal "BOTTOM")
		(9 "F.Adhes" user "F.Adhesive")
		(11 "B.Adhes" user "B.Adhesive")
		(13 "F.Paste" user "Package Geometry/Pastemask Top")
		(15 "B.Paste" user "Package Geometry/Pastemask Bottom")
		(5 "F.SilkS" user "Ref Des/Silkscreen Top")
		(7 "B.SilkS" user "Ref Des/Silkscreen Bottom")
		(1 "F.Mask" user "Board Geometry/Soldermask Top")
		(3 "B.Mask" user "Board Geometry/Soldermask Bottom")
		(17 "Dwgs.User" user "User.Drawings")
		(19 "Cmts.User" user "User.Comments")
		(21 "Eco1.User" user "User.Eco1")
		(23 "Eco2.User" user "User.Eco2")
		(25 "Edge.Cuts" user "Board Geometry/Outline")
		(27 "Margin" user)
		(31 "F.CrtYd" user "Package Geometry/Place Bound Top")
		(29 "B.CrtYd" user "Package Geometry/Place Bound Bottom")
		(35 "F.Fab" user "Ref Des/Assembly Top")
		(33 "B.Fab" user "Ref Des/Assembly Bottom")
	)
	(footprint ""
		(layer "F.Cu")
		(at 185.799222 -22.097492 180)
		(property "Reference" "PR4002"
			(at 0 0 180)
			(layer "F.SilkS")
			(hide yes)
			(effects
				(font
					(size 1.27 1.27)
				)
			)
		)
		(property "Value" ""
			(at 0 0 180)
			(layer "F.Fab")
			(effects
				(font
					(size 1.27 1.27)
				)
			)
		)
		(duplicate_pad_numbers_are_jumpers no)
		(fp_line
			(start 0.7874 0.4064)
			(end -0.7874 0.4064)
			(stroke
				(width 0.1524)
				(type default)
			)
			(layer "F.SilkS")
		)
		(fp_line
			(start 0.7874 -0.4064)
			(end 0.7874 0.4064)
			(stroke
				(width 0.1524)
				(type default)
			)
			(layer "F.SilkS")
		)
		(fp_line
			(start -0.7874 0.4064)
			(end -0.7874 -0.4064)
			(stroke
				(width 0.1524)
				(type default)
			)
			(layer "F.SilkS")
		)
		(fp_line
			(start -0.7874 -0.4064)
			(end 0.7874 -0.4064)
			(stroke
				(width 0.1524)
				(type default)
			)
			(layer "F.SilkS")
		)
		(fp_line
			(start 0.67945 0.3048)
			(end 0.120396 0.3048)
			(stroke
				(width 0.1)
				(type default)
			)
			(layer "F.Fab")
		)
		(fp_line
			(start 0.67945 -0.3048)
			(end 0.67945 0.3048)
			(stroke
				(width 0.1)
				(type default)
			)
			(layer "F.Fab")
		)
		(fp_line
			(start 0.12065 -0.2794)
			(end 0.12065 -0.3048)
			(stroke
				(width 0.1)
				(type default)
			)
			(layer "F.Fab")
		)
		(fp_line
			(start 0.12065 -0.3048)
			(end 0.67945 -0.3048)
			(stroke
				(width 0.1)
				(type default)
			)
			(layer "F.Fab")
		)
		(fp_line
			(start 0.120396 0.3048)
			(end 0.120396 0.2794)
			(stroke
				(width 0.1)
				(type default)
			)
			(layer "F.Fab")
		)
		(fp_line
			(start 0.120396 0.2794)
			(end -0.12065 0.2794)
			(stroke
				(width 0.1)
				(type default)
			)
			(layer "F.Fab")
		)
		(fp_line
			(start -0.12065 0.3048)
			(end -0.67945 0.3048)
			(stroke
				(width 0.1)
				(type default)
			)
			(layer "F.Fab")
		)
		(fp_line
			(start -0.12065 0.2794)
			(end -0.12065 0.3048)
			(stroke
				(width 0.1)
				(type default)
			)
			(layer "F.Fab")
		)
		(fp_line
			(start -0.12065 -0.2794)
			(end 0.12065 -0.2794)
			(stroke
				(width 0.1)
				(type default)
			)
			(layer "F.Fab")
		)
		(fp_line
			(start -0.12065 -0.305054)
			(end -0.12065 -0.2794)
			(stroke
				(width 0.1)
				(type default)
			)
			(layer "F.Fab")
		)
		(fp_line
			(start -0.67945 0.3048)
			(end -0.67945 -0.305054)
			(stroke
				(width 0.1)
				(type default)
			)
			(layer "F.Fab")
		)
		(fp_line
			(start -0.67945 -0.305054)
			(end -0.12065 -0.305054)
			(stroke
				(width 0.1)
				(type default)
			)
			(layer "F.Fab")
		)
		(pad "1" smd circle
			(at -0.40005 0 180)
			(size 0 0)
			(layers "F.Cu" "F.Mask" "F.Paste")
			(net "P12V_SCM_OV")
		)
		(pad "2" smd circle
			(at 0.40005 0 180)
			(size 0 0)
			(layers "F.Cu" "F.Mask" "F.Paste")
			(net "GND")
		)
	)
	(footprint ""
		(layer "F.Cu")
		(at 68.225162 -34.874708 180)
		(property "Reference" "R1181"
			(at 0 0 180)
			(layer "F.SilkS")
			(hide yes)
			(effects
				(font
					(size 1.27 1.27)
				)
			)
		)
		(property "Value" ""
			(at 0 0 180)
			(layer "F.Fab")
			(effects
				(font
					(size 1.27 1.27)
				)
			)
		)
		(duplicate_pad_numbers_are_jumpers no)
		(fp_line
			(start 0.7874 0.4064)
			(end -0.7874 0.4064)
			(stroke
				(width 0.1524)
				(type default)
			)
			(layer "F.SilkS")
		)
		(fp_line
			(start 0.7874 -0.4064)
			(end 0.7874 0.4064)
			(stroke
				(width 0.1524)
				(type default)
			)
			(layer "F.SilkS")
		)
		(fp_line
			(start -0.7874 0.4064)
			(end -0.7874 -0.4064)
			(stroke
				(width 0.1524)
				(type default)
			)
			(layer "F.SilkS")
		)
		(fp_line
			(start -0.7874 -0.4064)
			(end 0.7874 -0.4064)
			(stroke
				(width 0.1524)
				(type default)
			)
			(layer "F.SilkS")
		)
		(fp_line
			(start 0.67945 0.3048)
			(end 0.120396 0.3048)
			(stroke
				(width 0.1)
				(type default)
			)
			(layer "F.Fab")
		)
		(fp_line
			(start 0.67945 -0.3048)
			(end 0.67945 0.3048)
			(stroke
				(width 0.1)
				(type default)
			)
			(layer "F.Fab")
		)
		(fp_line
			(start 0.12065 -0.2794)
			(end 0.12065 -0.3048)
			(stroke
				(width 0.1)
				(type default)
			)
			(layer "F.Fab")
		)
		(fp_line
			(start 0.12065 -0.3048)
			(end 0.67945 -0.3048)
			(stroke
				(width 0.1)
				(type default)
			)
			(layer "F.Fab")
		)
		(fp_line
			(start 0.120396 0.3048)
			(end 0.120396 0.2794)
			(stroke
				(width 0.1)
				(type default)
			)
			(layer "F.Fab")
		)
		(fp_line
			(start 0.120396 0.2794)
			(end -0.12065 0.2794)
			(stroke
				(width 0.1)
				(type default)
			)
			(layer "F.Fab")
		)
		(fp_line
			(start -0.12065 0.3048)
			(end -0.67945 0.3048)
			(stroke
				(width 0.1)
				(type default)
			)
			(layer "F.Fab")
		)
		(fp_line
			(start -0.12065 0.2794)
			(end -0.12065 0.3048)
			(stroke
				(width 0.1)
				(type default)
			)
			(layer "F.Fab")
		)
		(fp_line
			(start -0.12065 -0.2794)
			(end 0.12065 -0.2794)
			(stroke
				(width 0.1)
				(type default)
			)
			(layer "F.Fab")
		)
		(fp_line
			(start -0.12065 -0.305054)
			(end -0.12065 -0.2794)
			(stroke
				(width 0.1)
				(type default)
			)
			(layer "F.Fab")
		)
		(fp_line
			(start -0.67945 0.3048)
			(end -0.67945 -0.305054)
			(stroke
				(width 0.1)
				(type default)
			)
			(layer "F.Fab")
		)
		(fp_line
			(start -0.67945 -0.305054)
			(end -0.12065 -0.305054)
			(stroke
				(width 0.1)
				(type default)
			)
			(layer "F.Fab")
		)
		(pad "1" smd circle
			(at -0.40005 0 180)
			(size 0 0)
			(layers "F.Cu" "F.Mask" "F.Paste")
			(net "P12V_OCP_V3_2_BUF_EN_R")
		)
		(pad "2" smd circle
			(at 0.40005 0 180)
			(size 0 0)
			(layers "F.Cu" "F.Mask" "F.Paste")
			(net "P12V_OCP_EN_2_R")
		)
	)
)
